#ISCELL
  mstr_symbols cad_note *
  *
#ISCELL
  mstr_symbols design_note *
  *
#ISCELL
  mstr_symbols intel_corp_bpage *
  *
#CELL
  dev_discrete cap_a *
  page186_i10
#ISCELL
  mstr_symbols gnd *
  page186_i14
#ISCELL
  mstr_symbols gnd *
  page186_i192
#ISCELL
  mstr_symbols gnd *
  page186_i193
#ISCELL
  mstr_symbols p3v3 *
  page186_i195
#ISCELL
  mstr_standard offpage *
  page186_i217
#CELL
  mstr_discrete res *
  page186_i220
#ISCELL
  mstr_standard offpage *
  page186_i221
#ISCELL
  mstr_symbols gnd *
  page186_i223
#ISCELL
  mstr_standard offpage *
  page186_i227
#ISCELL
  mstr_standard offpage *
  page186_i228
#ISCELL
  mstr_standard offpage *
  page186_i229
#ISCELL
  mstr_standard offpage *
  page186_i233
#ISCELL
  mstr_standard offpage *
  page186_i234
#ISCELL
  mstr_symbols p3v3 *
  page186_i247
#ISCELL
  mstr_standard offpage *
  page186_i249
#ISCELL
  mstr_standard offpage *
  page186_i250
#ISCELL
  mstr_standard offpage *
  page186_i251
#ISCELL
  mstr_standard offpage *
  page186_i252
#ISCELL
  mstr_standard offpage *
  page186_i254
#ISCELL
  mstr_standard offpage *
  page186_i255
#ISCELL
  mstr_standard offpage *
  page186_i256
#ISCELL
  mstr_standard offpage *
  page186_i257
#ISCELL
  mstr_symbols p3v3 *
  page186_i268
#ISCELL
  mstr_symbols gnd *
  page186_i269
#CELL
  dev_discrete cap_a *
  page186_i270
#ISCELL
  mstr_symbols p3v3_stby *
  page186_i274
#ISCELL
  mstr_symbols p3v3_stby *
  page186_i275
#ISCELL
  mstr_symbols p5v_stby *
  page186_i276
#ISCELL
  mstr_symbols p12v_stby *
  page186_i278
#ISCELL
  mstr_symbols p12v_stby *
  page186_i279
#ISCELL
  mstr_symbols p3v3_stby *
  page186_i296
#ISCELL
  mstr_standard tap *
  page186_i297
#ISCELL
  mstr_standard tap *
  page186_i298
#ISCELL
  mstr_standard tap *
  page186_i299
#CELL
  mstr_discrete cap *
  page186_i3
#ISCELL
  mstr_standard tap *
  page186_i300
#ISCELL
  mstr_standard tap *
  page186_i301
#ISCELL
  mstr_standard tap *
  page186_i302
#ISCELL
  mstr_standard tap *
  page186_i303
#ISCELL
  mstr_standard tap *
  page186_i304
#ISCELL
  mstr_standard tap *
  page186_i305
#ISCELL
  mstr_standard tap *
  page186_i306
#ISCELL
  mstr_standard tap *
  page186_i307
#ISCELL
  mstr_standard tap *
  page186_i308
#ISCELL
  mstr_standard tap *
  page186_i309
#ISCELL
  mstr_standard tap *
  page186_i310
#ISCELL
  mstr_standard tap *
  page186_i311
#ISCELL
  mstr_standard tap *
  page186_i312
#ISCELL
  mstr_standard offpage *
  page186_i313
#ISCELL
  mstr_standard offpage *
  page186_i314
#ISCELL
  mstr_standard tap *
  page186_i315
#ISCELL
  mstr_standard tap *
  page186_i316
#ISCELL
  mstr_standard tap *
  page186_i317
#ISCELL
  mstr_standard tap *
  page186_i318
#ISCELL
  mstr_standard offpage *
  page186_i320
#ISCELL
  mstr_standard tap *
  page186_i321
#ISCELL
  mstr_standard tap *
  page186_i322
#ISCELL
  mstr_standard tap *
  page186_i323
#ISCELL
  mstr_standard tap *
  page186_i324
#ISCELL
  mstr_standard tap *
  page186_i325
#ISCELL
  mstr_standard tap *
  page186_i326
#ISCELL
  mstr_standard tap *
  page186_i327
#ISCELL
  mstr_standard tap *
  page186_i328
#ISCELL
  mstr_standard tap *
  page186_i329
#ISCELL
  mstr_standard tap *
  page186_i330
#ISCELL
  mstr_standard tap *
  page186_i331
#ISCELL
  mstr_standard tap *
  page186_i332
#ISCELL
  mstr_standard offpage *
  page186_i333
#CELL
  dev_discrete cap_a *
  page186_i334
#CELL
  dev_discrete cap_a *
  page186_i335
#CELL
  mstr_sconn sconn120_a28699018 *
  page186_i336
#CELL
  mstr_discrete res *
  page186_i337
#CELL
  mstr_discrete res *
  page186_i338
#CELL
  mstr_discrete res *
  page186_i339
#CELL
  mstr_discrete res *
  page186_i340
#ISCELL
  mstr_standard offpage *
  page186_i341
#ISCELL
  mstr_standard offpage *
  page186_i342
#ISCELL
  mstr_standard offpage *
  page186_i343
#ISCELL
  mstr_standard offpage *
  page186_i344
#CELL
  dev_discrete cap_a *
  page186_i345
#ISCELL
  mstr_symbols gnd *
  page186_i346
#ISCELL
  mstr_symbols p5v_stby *
  page186_i348
#ISCELL
  mstr_symbols p3v3_stby *
  page186_i350
#ISCELL
  mstr_standard offpage *
  page186_i354
#CELL
  mstr_discrete res *
  page186_i356
#CELL
  w_hdl sc1u10v2kx-4-gp *
  page186_i357
#CELL
  w_hdl 887r2f-l-gp *
  page186_i358
#CELL
  mstr_discrete cap *
  page186_i6
#CELL
  dev_discrete cap_a *
  page186_i7
#CELL
  dev_discrete cap_a *
  page186_i8
#ISCELL
  mstr_symbols gnd *
  page186_i9
